# PolarFire SoM — assets/stackup.csv
Name;Type;Material;Thickness[mm];Constant;User-Name
F.Mask;Top Solder Mask;;0.03;;F_Mask
F.Cu;copper;;0.035;;F_Cu
dielectric 1;prepreg;PR2313;0.0964;4.31;dielectric 1
In1.Cu;copper;;0.0152;;In1_Cu
dielectric 2;core;S1000-2M;0.1;4.35;dielectric 2
In2.Cu;copper;;0.0152;;In2_Cu
dielectric 3;prepreg;PR2116;0.1118;4.29;dielectric 3
In3.Cu;copper;;0.0152;;In3_Cu
dielectric 4;core;S1000-2M;0.1;4.35;dielectric 4
In4.Cu;copper;;0.0152;;In4_Cu
dielectric 5;prepreg;PR2116;0.1118;4.29;dielectric 5
In5.Cu;copper;;0.0152;;In5_Cu
dielectric 6;core;S1000-2M;0.1;4.35;dielectric 6
In6.Cu;copper;;0.0152;;In6_Cu
dielectric 7;prepreg;PR2116;0.1118;4.29;dielectric 7
In7.Cu;copper;;0.0152;;In7_Cu
dielectric 8;core;S1000-2M;0.1;4.35;dielectric 8
In8.Cu;copper;;0.0152;;In8_Cu
dielectric 9;prepreg;PR2116;0.1118;4.29;dielectric 9
In9.Cu;copper;;0.0152;;In9_Cu
dielectric 10;core;S1000-2M;0.1;4.35;dielectric 10
In10.Cu;copper;;0.0152;;In10_Cu
dielectric 11;prepreg;PR2116;0.1118;4.31;dielectric 11
In11.Cu;copper;;0.0152;;In11_Cu
dielectric 12;core;S1000-2M;0.1;4.5;dielectric 12
In12.Cu;copper;;0.0152;;In12_Cu
dielectric 13;prepreg;PR2313;0.0964;4.5;dielectric 13
B.Cu;copper;;0.035;;B_Cu
B.Mask;Bottom Solder Mask;;0.03;;B_Mask
